# S9S_MB_2U (Grand Teton) — schematic netlist excerpt (pin names and nets, part order shuffled) for the footprints in the layout excerpt that follows; sources: Cadence DE-HDL packaged netlist, KiCad conversion of 03242023_DA0F0TMBIJ0_F0T_Motherboard_J_brd_V01_OCP.brd

R73  Q_RES  127K 1% CHIP  pkg 0402LF  page 112 : A = PD_CHH_CPU1_DIMM1_SAA ; B = GND
R4279  Q_RES  1K 1% EMPTY  pkg 0402LF  page 169 : A = P3V3_AUX ; B = FM_USB3_1_FGA

(kicad_pcb
	(version 20260206)
	(generator "pcbnew")
	(generator_version "10.0")
	(general
		(thickness 1.6)
		(legacy_teardrops no)
	)
	(paper "A4")
	(title_block
		(title "03242023_DA0F0TMBIJ0_F0T_Motherboard_J_brd_V01_OCP.brd")
		(comment 1 "Grand Teton / footprints 4599-4600 of 6105")
	)
	(layers
		(0 "F.Cu" signal "TOP")
		(4 "In1.Cu" signal "GND")
		(6 "In2.Cu" signal "IN1")
		(8 "In3.Cu" signal "GND1")
		(10 "In4.Cu" signal "IN2")
		(12 "In5.Cu" signal "GND2")
		(14 "In6.Cu" signal "IN3")
		(16 "In7.Cu" signal "GND3")
		(18 "In8.Cu" signal "VCC")
		(20 "In9.Cu" signal "VCC1")
		(22 "In10.Cu" signal "GND4")
		(24 "In11.Cu" signal "IN4")
		(26 "In12.Cu" signal "GND5")
		(28 "In13.Cu" signal "IN5")
		(30 "In14.Cu" signal "GND6")
		(32 "In15.Cu" signal "IN6")
		(34 "In16.Cu" signal "GND7")
		(2 "B.Cu" signal "BOTTOM")
		(9 "F.Adhes" user "F.Adhesive")
		(11 "B.Adhes" user "B.Adhesive")
		(13 "F.Paste" user "Package Geometry/Pastemask Top")
		(15 "B.Paste" user "Package Geometry/Pastemask Bottom")
		(5 "F.SilkS" user "Ref Des/Silkscreen Top")
		(7 "B.SilkS" user "Ref Des/Silkscreen Bottom")
		(1 "F.Mask" user "Board Geometry/Soldermask Top")
		(3 "B.Mask" user "Board Geometry/Soldermask Bottom")
		(17 "Dwgs.User" user "User.Drawings")
		(19 "Cmts.User" user "User.Comments")
		(21 "Eco1.User" user "User.Eco1")
		(23 "Eco2.User" user "User.Eco2")
		(25 "Edge.Cuts" user "Board Geometry/Outline")
		(27 "Margin" user)
		(31 "F.CrtYd" user "Package Geometry/Place Bound Top")
		(29 "B.CrtYd" user "Package Geometry/Place Bound Bottom")
		(35 "F.Fab" user "Ref Des/Assembly Top")
		(33 "B.Fab" user "Ref Des/Assembly Bottom")
	)
	(footprint ""
		(layer "B.Cu")
		(at 213.58098 -318.107568)
		(property "Reference" "R73"
			(at 0 0 0)
			(layer "B.SilkS")
			(hide yes)
			(effects
				(font
					(size 1.27 1.27)
				)
				(justify mirror)
			)
		)
		(property "Value" ""
			(at 0 0 0)
			(layer "B.Fab")
			(effects
				(font
					(size 1.27 1.27)
				)
				(justify mirror)
			)
		)
		(duplicate_pad_numbers_are_jumpers no)
		(fp_line
			(start -0.7874 -0.4064)
			(end -0.7874 0.4064)
			(stroke
				(width 0.1524)
				(type default)
			)
			(layer "B.SilkS")
		)
		(fp_line
			(start -0.7874 0.4064)
			(end 0.7874 0.4064)
			(stroke
				(width 0.1524)
				(type default)
			)
			(layer "B.SilkS")
		)
		(fp_line
			(start 0.7874 -0.4064)
			(end -0.7874 -0.4064)
			(stroke
				(width 0.1524)
				(type default)
			)
			(layer "B.SilkS")
		)
		(fp_line
			(start 0.7874 0.4064)
			(end 0.7874 -0.4064)
			(stroke
				(width 0.1524)
				(type default)
			)
			(layer "B.SilkS")
		)
		(fp_line
			(start -0.67945 -0.3048)
			(end -0.67945 0.3048)
			(stroke
				(width 0.1)
				(type default)
			)
			(layer "B.Fab")
		)
		(fp_line
			(start -0.67945 0.3048)
			(end -0.120396 0.3048)
			(stroke
				(width 0.1)
				(type default)
			)
			(layer "B.Fab")
		)
		(fp_line
			(start -0.12065 -0.3048)
			(end -0.67945 -0.3048)
			(stroke
				(width 0.1)
				(type default)
			)
			(layer "B.Fab")
		)
		(fp_line
			(start -0.12065 -0.2794)
			(end -0.12065 -0.3048)
			(stroke
				(width 0.1)
				(type default)
			)
			(layer "B.Fab")
		)
		(fp_line
			(start -0.120396 0.2794)
			(end 0.12065 0.2794)
			(stroke
				(width 0.1)
				(type default)
			)
			(layer "B.Fab")
		)
		(fp_line
			(start -0.120396 0.3048)
			(end -0.120396 0.2794)
			(stroke
				(width 0.1)
				(type default)
			)
			(layer "B.Fab")
		)
		(fp_line
			(start 0.12065 -0.305054)
			(end 0.12065 -0.2794)
			(stroke
				(width 0.1)
				(type default)
			)
			(layer "B.Fab")
		)
		(fp_line
			(start 0.12065 -0.2794)
			(end -0.12065 -0.2794)
			(stroke
				(width 0.1)
				(type default)
			)
			(layer "B.Fab")
		)
		(fp_line
			(start 0.12065 0.2794)
			(end 0.12065 0.3048)
			(stroke
				(width 0.1)
				(type default)
			)
			(layer "B.Fab")
		)
		(fp_line
			(start 0.12065 0.3048)
			(end 0.67945 0.3048)
			(stroke
				(width 0.1)
				(type default)
			)
			(layer "B.Fab")
		)
		(fp_line
			(start 0.67945 -0.305054)
			(end 0.12065 -0.305054)
			(stroke
				(width 0.1)
				(type default)
			)
			(layer "B.Fab")
		)
		(fp_line
			(start 0.67945 0.3048)
			(end 0.67945 -0.305054)
			(stroke
				(width 0.1)
				(type default)
			)
			(layer "B.Fab")
		)
		(pad "1" smd circle
			(at 0.40005 0 180)
			(size 0 0)
			(layers "B.Cu" "B.Mask" "B.Paste")
			(net "PD_CHH_CPU1_DIMM1_SAA")
		)
		(pad "2" smd circle
			(at -0.40005 0 180)
			(size 0 0)
			(layers "B.Cu" "B.Mask" "B.Paste")
			(net "GND")
		)
	)
	(footprint ""
		(layer "B.Cu")
		(at 128.85674 -18.539968 -90)
		(property "Reference" "R4279"
			(at 0 0 90)
			(layer "B.SilkS")
			(hide yes)
			(effects
				(font
					(size 1.27 1.27)
				)
				(justify mirror)
			)
		)
		(property "Value" ""
			(at 0 0 90)
			(layer "B.Fab")
			(effects
				(font
					(size 1.27 1.27)
				)
				(justify mirror)
			)
		)
		(duplicate_pad_numbers_are_jumpers no)
		(fp_line
			(start -0.7874 0.4064)
			(end 0.7874 0.4064)
			(stroke
				(width 0.1524)
				(type default)
			)
			(layer "B.SilkS")
		)
		(fp_line
			(start 0.7874 0.4064)
			(end 0.7874 -0.4064)
			(stroke
				(width 0.1524)
				(type default)
			)
			(layer "B.SilkS")
		)
		(fp_line
			(start -0.7874 -0.4064)
			(end -0.7874 0.4064)
			(stroke
				(width 0.1524)
				(type default)
			)
			(layer "B.SilkS")
		)
		(fp_line
			(start 0.7874 -0.4064)
			(end -0.7874 -0.4064)
			(stroke
				(width 0.1524)
				(type default)
			)
			(layer "B.SilkS")
		)
		(fp_line
			(start -0.67945 0.3048)
			(end -0.120396 0.3048)
			(stroke
				(width 0.1)
				(type default)
			)
			(layer "B.Fab")
		)
		(fp_line
			(start -0.120396 0.3048)
			(end -0.120396 0.2794)
			(stroke
				(width 0.1)
				(type default)
			)
			(layer "B.Fab")
		)
		(fp_line
			(start 0.12065 0.3048)
			(end 0.67945 0.3048)
			(stroke
				(width 0.1)
				(type default)
			)
			(layer "B.Fab")
		)
		(fp_line
			(start 0.67945 0.3048)
			(end 0.67945 -0.305054)
			(stroke
				(width 0.1)
				(type default)
			)
			(layer "B.Fab")
		)
		(fp_line
			(start -0.120396 0.2794)
			(end 0.12065 0.2794)
			(stroke
				(width 0.1)
				(type default)
			)
			(layer "B.Fab")
		)
		(fp_line
			(start 0.12065 0.2794)
			(end 0.12065 0.3048)
			(stroke
				(width 0.1)
				(type default)
			)
			(layer "B.Fab")
		)
		(fp_line
			(start -0.12065 -0.2794)
			(end -0.12065 -0.3048)
			(stroke
				(width 0.1)
				(type default)
			)
			(layer "B.Fab")
		)
		(fp_line
			(start 0.12065 -0.2794)
			(end -0.12065 -0.2794)
			(stroke
				(width 0.1)
				(type default)
			)
			(layer "B.Fab")
		)
		(fp_line
			(start -0.67945 -0.3048)
			(end -0.67945 0.3048)
			(stroke
				(width 0.1)
				(type default)
			)
			(layer "B.Fab")
		)
		(fp_line
			(start -0.12065 -0.3048)
			(end -0.67945 -0.3048)
			(stroke
				(width 0.1)
				(type default)
			)
			(layer "B.Fab")
		)
		(fp_line
			(start 0.12065 -0.305054)
			(end 0.12065 -0.2794)
			(stroke
				(width 0.1)
				(type default)
			)
			(layer "B.Fab")
		)
		(fp_line
			(start 0.67945 -0.305054)
			(end 0.12065 -0.305054)
			(stroke
				(width 0.1)
				(type default)
			)
			(layer "B.Fab")
		)
		(pad "1" smd circle
			(at 0.40005 0 90)
			(size 0 0)
			(layers "B.Cu" "B.Mask" "B.Paste")
			(net "P3V3_AUX")
		)
		(pad "2" smd circle
			(at -0.40005 0 90)
			(size 0 0)
			(layers "B.Cu" "B.Mask" "B.Paste")
			(net "FM_USB3_1_FGA")
		)
	)
)
